# T6G (Grand Teton) — schematic netlist excerpt (pin names and nets, part order shuffled) for the footprints in the layout excerpt that follows; sources: Cadence DE-HDL packaged netlist, KiCad conversion of 04192023_DAF0TMB3IC0_F0TG_MB_C_brd_V02_OCP.brd

U6002  TUSB8042AIRGCR  IC  pkg VQFN64_TH_0-5_9X9XC  page 178
  USB_DP_DN1  = USB_HUB2_TI_USB_DP_DN1_MRP_CFG_STRAP
  USB_DM_DN1  = NC
  USB_SSTXP_DN1  = NC
  USB_SSTXM_DN1  = NC
  VDD_5  = USB_HUB2_TI_VDD_MRP_USB3DN_TXDM1
  USB_SSRXP_DN1  = USB_HUB2_TI_USB_SSRXP_DN1_MRP_VDD12
  USB_SSRXM_DN1  = NC
  VDD_8  = USB_HUB2_TI_VDD_MRP_USB3DN_RXDM1
  USB_DP_DN2  = USB2_CPU0_P0_HUB2_R_DP
  USB_DM_DN2  = USB2_CPU0_P0_HUB2_R_DN
  USB_SSTXP_DN2  = USB3_CPU0_BMC_HUB2_TX_DP
  USB_SSTXM_DN2  = USB3_CPU0_BMC_HUB2_TX_DN
  VDD_13  = P1V2_CPU0_USB2_DVDD12
  USB_SSRXP_DN2  = USB3_CPU0_BMC_RX_C2_DP
  USB_SSRXM_DN2  = USB3_CPU0_BMC_RX_C2_DN
  VDD33_16  = USB_HUB2_TI_VDD33_MRP_PROG_FUNC7
  USB_DP_DN3  = USB_HUB2_TI_USB_DP_DN3_MRP_VDD12
  USB_DM_DN3  = USB_HUB2_TI_USB_DM_DN3_MRP_VDD33
  USB_SSTXP_DN3  = NC
  USB_SSTXM_DN3  = NC
  VDD_21  = USB_HUB2_TI_VDD_MRP_USB3DN_TXDP3
  USB_SSRXP_DN3  = NC
  USB_SSRXM_DN3  = USB_HUB2_TI_USB_SSRXM_DN3_MRP_VDD12
  USB_DP_DN4  = NC
  USB_DM_DN4  = NC
  USB_SSTXP_DN4  = NC
  USB_SSTXM_DN4  = NC
  VDD_28  = USB_HUB2_TI_VDD_MRP_USB3DN_TXDP4
  USB_SSRXP_DN4  = NC
  USB_SSRXM_DN4  = USB_HUB2_TI_USB_SSRXM_DN4_MRP_VDD12
  VDD_31  = USB_HUB2_TI_VDD_MRP_USB3DN_RXDP4
  \pwrctl4||baten4\  = NC
  \pwrctl3||baten3\  = USB_HUB2_TI_PWRCTL3_MRP_VDD33
  VDD33_34  = USB_HUB2_TI_VDD33_MRP_PRT_CTL4_GANGPWR
  \pwrctl2||baten2\  = USB_HUB2_TI_PWRCTL2_MRP_VDD12
  \pwrctl1||baten1\  = NC
  \sda||smbdat\  = SMB_USB_HUB2_TI_SDA_MRP_PRT_CTL2
  \scl||smbclk\  = SMB_USB_HUB2_TI_SCL_MRP_PRT_CTL1
  \smbusz||ss_suspend\  = USB_HUB2_TI_SMBUSZ_MRP_PROG_FUNC2
  \fullpwrmgmtz||fullautoz||smba1||ss_up\  = USB_HUB2_TI_FULLPWRMGMTZ_MRP_PROG_FUNC3
  PWRCTL_POL  = USB_HUB2_TI_PWRCTL_POL_MRP_VBUS_DET
  \ganged||smba2||hs_up\  = USB_HUB2_TI_GANGED_MRP_I2C_SLV_CFG0
  OVERCUR4Z  = USB_HUB2_TI_OVERCUR4_MRP_I2C_SLV_CFG1
  OVERCUR3Z  = USB_HUB2_TI_OVERCUR3_MRP_CFG_BC_EN
  \autoenz||hs_suspend\  = USB_HUB2_TI_HS_SUSPEND_MRP_CFG_NON_REM
  OVERCUR1Z  = USB_HUB2_TI_OVERCUR1_MRP_PROG_FUNC4
  OVERCUR2Z  = USB_HUB2_TI_OVERCUR2_MRP_PROG_FUNC5
  USB_VBUS  = USB_HUB2_TI_USB_VBUS_MRP_RESET_N
  TEST  = USB_HUB2_TI_TEST_MRP_PROG_FUNC6
  GRSTZ  = USB_HUB2_TI_GRSTZ_MRP_PROG_FUNC1
  VDD_51  = P1V2_CPU0_USB2_DVDD12
  VDD33_52  = P3V3_AUX_CPU0_USB2_AVDD33
  USB_DP_UP  = USB2_CPU0_P0_R2_DP
  USB_DM_UP  = USB2_CPU0_P0_R2_DN
  USB_SSTXP_UP  = USB3_CPU0_BMC_RX_HUB2_DP
  USB_SSTXM_UP  = USB3_CPU0_BMC_RX_HUB2_DN
  VDD_57  = P1V2_CPU0_USB2_DVDD12
  USB_SSRXP_UP  = USB3_CPU0_BMC_TX_C2_DP
  USB_SSRXM_UP  = USB3_CPU0_BMC_TX_C2_DN
  NC_1  = USB_HUB2_TI_NC_MRP_ATEST
  XO  = XTAL_USB_CPU0_HUB2_XOUT
  XI  = XTAL_USB_CPU0_HUB2_XIN
  VDD33_63  = P3V3_AUX_CPU0_USB2_AVDD33
  USB_R1  = USB_HUB2_TI_USB_R1_MRP_RBIAS
  TH_VSS  = GND

(kicad_pcb
	(version 20260206)
	(generator "pcbnew")
	(generator_version "10.0")
	(general
		(thickness 1.6)
		(legacy_teardrops no)
	)
	(paper "A4")
	(title_block
		(title "04192023_DAF0TMB3IC0_F0TG_MB_C_brd_V02_OCP.brd")
		(comment 1 "Grand Teton / footprint 2863 of 8354 (U6002), pads 1-44 of 65")
	)
	(layers
		(0 "F.Cu" signal "TOP")
		(4 "In1.Cu" signal "GND")
		(6 "In2.Cu" signal "IN1")
		(8 "In3.Cu" signal "GND1")
		(10 "In4.Cu" signal "IN2")
		(12 "In5.Cu" signal "GND2")
		(14 "In6.Cu" signal "IN3")
		(16 "In7.Cu" signal "GND3")
		(18 "In8.Cu" signal "VCC")
		(20 "In9.Cu" signal "VCC1")
		(22 "In10.Cu" signal "GND4")
		(24 "In11.Cu" signal "IN4")
		(26 "In12.Cu" signal "GND5")
		(28 "In13.Cu" signal "IN5")
		(30 "In14.Cu" signal "GND6")
		(32 "In15.Cu" signal "IN6")
		(34 "In16.Cu" signal "GND7")
		(2 "B.Cu" signal "BOTTOM")
		(9 "F.Adhes" user "F.Adhesive")
		(11 "B.Adhes" user "B.Adhesive")
		(13 "F.Paste" user "Package Geometry/Pastemask Top")
		(15 "B.Paste" user "Package Geometry/Pastemask Bottom")
		(5 "F.SilkS" user "Ref Des/Silkscreen Top")
		(7 "B.SilkS" user "Ref Des/Silkscreen Bottom")
		(1 "F.Mask" user "Board Geometry/Soldermask Top")
		(3 "B.Mask" user "Board Geometry/Soldermask Bottom")
		(17 "Dwgs.User" user "User.Drawings")
		(19 "Cmts.User" user "User.Comments")
		(21 "Eco1.User" user "User.Eco1")
		(23 "Eco2.User" user "User.Eco2")
		(25 "Edge.Cuts" user "Board Geometry/Outline")
		(27 "Margin" user)
		(31 "F.CrtYd" user "Package Geometry/Place Bound Top")
		(29 "B.CrtYd" user "Package Geometry/Place Bound Bottom")
		(35 "F.Fab" user "Ref Des/Assembly Top")
		(33 "B.Fab" user "Ref Des/Assembly Bottom")
	)
	(footprint ""
		(layer "F.Cu")
		(at 112.79886 -31.497778 90)
		(property "Reference" "U6002"
			(at -4.285742 -6.178804 90)
			(unlocked yes)
			(layer "F.SilkS")
			(effects
				(font
					(size 0.7874 0.5842)
					(thickness 0.1524)
				)
				(justify left)
			)
		)
		(property "Value" ""
			(at 0 0 90)
			(layer "F.Fab")
			(effects
				(font
					(size 1.27 1.27)
				)
			)
		)
		(duplicate_pad_numbers_are_jumpers no)
		(pad "1" smd circle
			(at -4.400042 -3.750056)
			(size 0 0)
			(layers "F.Cu" "F.Mask" "F.Paste")
			(net "USB_HUB2_TI_USB_DP_DN1_MRP_CFG_STRAP")
		)
		(pad "2" smd circle
			(at -4.400042 -3.24993)
			(size 0 0)
			(layers "F.Cu" "F.Mask" "F.Paste")
			(net "Net_10829")
		)
		(pad "3" smd circle
			(at -4.400042 -2.750058)
			(size 0 0)
			(layers "F.Cu" "F.Mask" "F.Paste")
			(net "Net_10820")
		)
		(pad "4" smd circle
			(at -4.400042 -2.249932)
			(size 0 0)
			(layers "F.Cu" "F.Mask" "F.Paste")
			(net "Net_10823")
		)
		(pad "5" smd circle
			(at -4.400042 -1.75006)
			(size 0 0)
			(layers "F.Cu" "F.Mask" "F.Paste")
			(net "USB_HUB2_TI_VDD_MRP_USB3DN_TXDM1")
		)
		(pad "6" smd circle
			(at -4.400042 -1.249934)
			(size 0 0)
			(layers "F.Cu" "F.Mask" "F.Paste")
			(net "USB_HUB2_TI_USB_SSRXP_DN1_MRP_VDD12")
		)
		(pad "7" smd circle
			(at -4.400042 -0.750062)
			(size 0 0)
			(layers "F.Cu" "F.Mask" "F.Paste")
			(net "Net_10826")
		)
		(pad "8" smd circle
			(at -4.400042 -0.249936)
			(size 0 0)
			(layers "F.Cu" "F.Mask" "F.Paste")
			(net "USB_HUB2_TI_VDD_MRP_USB3DN_RXDM1")
		)
		(pad "9" smd circle
			(at -4.400042 0.249936)
			(size 0 0)
			(layers "F.Cu" "F.Mask" "F.Paste")
			(net "USB2_CPU0_P0_HUB2_R_DP")
		)
		(pad "10" smd circle
			(at -4.400042 0.750062)
			(size 0 0)
			(layers "F.Cu" "F.Mask" "F.Paste")
			(net "USB2_CPU0_P0_HUB2_R_DN")
		)
		(pad "11" smd circle
			(at -4.400042 1.249934)
			(size 0 0)
			(layers "F.Cu" "F.Mask" "F.Paste")
			(net "USB3_CPU0_BMC_HUB2_TX_DP")
		)
		(pad "12" smd circle
			(at -4.400042 1.75006)
			(size 0 0)
			(layers "F.Cu" "F.Mask" "F.Paste")
			(net "USB3_CPU0_BMC_HUB2_TX_DN")
		)
		(pad "13" smd circle
			(at -4.400042 2.249932)
			(size 0 0)
			(layers "F.Cu" "F.Mask" "F.Paste")
			(net "P1V2_CPU0_USB2_DVDD12")
		)
		(pad "14" smd circle
			(at -4.400042 2.750058)
			(size 0 0)
			(layers "F.Cu" "F.Mask" "F.Paste")
			(net "USB3_CPU0_BMC_RX_C2_DP")
		)
		(pad "15" smd circle
			(at -4.400042 3.24993)
			(size 0 0)
			(layers "F.Cu" "F.Mask" "F.Paste")
			(net "USB3_CPU0_BMC_RX_C2_DN")
		)
		(pad "16" smd circle
			(at -4.400042 3.750056)
			(size 0 0)
			(layers "F.Cu" "F.Mask" "F.Paste")
			(net "USB_HUB2_TI_VDD33_MRP_PROG_FUNC7")
		)
		(pad "17" smd circle
			(at -3.750056 4.400042 90)
			(size 0 0)
			(layers "F.Cu" "F.Mask" "F.Paste")
			(net "USB_HUB2_TI_USB_DP_DN3_MRP_VDD12")
		)
		(pad "18" smd circle
			(at -3.24993 4.400042 90)
			(size 0 0)
			(layers "F.Cu" "F.Mask" "F.Paste")
			(net "USB_HUB2_TI_USB_DM_DN3_MRP_VDD33")
		)
		(pad "19" smd circle
			(at -2.750058 4.400042 90)
			(size 0 0)
			(layers "F.Cu" "F.Mask" "F.Paste")
			(net "Net_10819")
		)
		(pad "20" smd circle
			(at -2.249932 4.400042 90)
			(size 0 0)
			(layers "F.Cu" "F.Mask" "F.Paste")
			(net "Net_10822")
		)
		(pad "21" smd circle
			(at -1.75006 4.400042 90)
			(size 0 0)
			(layers "F.Cu" "F.Mask" "F.Paste")
			(net "USB_HUB2_TI_VDD_MRP_USB3DN_TXDP3")
		)
		(pad "22" smd circle
			(at -1.249934 4.400042 90)
			(size 0 0)
			(layers "F.Cu" "F.Mask" "F.Paste")
			(net "Net_10825")
		)
		(pad "23" smd circle
			(at -0.750062 4.400042 90)
			(size 0 0)
			(layers "F.Cu" "F.Mask" "F.Paste")
			(net "USB_HUB2_TI_USB_SSRXM_DN3_MRP_VDD12")
		)
		(pad "24" smd circle
			(at -0.249936 4.400042 90)
			(size 0 0)
			(layers "F.Cu" "F.Mask" "F.Paste")
			(net "Net_10827")
		)
		(pad "25" smd circle
			(at 0.249936 4.400042 90)
			(size 0 0)
			(layers "F.Cu" "F.Mask" "F.Paste")
			(net "Net_10828")
		)
		(pad "26" smd circle
			(at 0.750062 4.400042 90)
			(size 0 0)
			(layers "F.Cu" "F.Mask" "F.Paste")
			(net "Net_10818")
		)
		(pad "27" smd circle
			(at 1.249934 4.400042 90)
			(size 0 0)
			(layers "F.Cu" "F.Mask" "F.Paste")
			(net "Net_10821")
		)
		(pad "28" smd circle
			(at 1.75006 4.400042 90)
			(size 0 0)
			(layers "F.Cu" "F.Mask" "F.Paste")
			(net "USB_HUB2_TI_VDD_MRP_USB3DN_TXDP4")
		)
		(pad "29" smd circle
			(at 2.249932 4.400042 90)
			(size 0 0)
			(layers "F.Cu" "F.Mask" "F.Paste")
			(net "Net_10824")
		)
		(pad "30" smd circle
			(at 2.750058 4.400042 90)
			(size 0 0)
			(layers "F.Cu" "F.Mask" "F.Paste")
			(net "USB_HUB2_TI_USB_SSRXM_DN4_MRP_VDD12")
		)
		(pad "31" smd circle
			(at 3.24993 4.400042 90)
			(size 0 0)
			(layers "F.Cu" "F.Mask" "F.Paste")
			(net "USB_HUB2_TI_VDD_MRP_USB3DN_RXDP4")
		)
		(pad "32" smd circle
			(at 3.750056 4.400042 90)
			(size 0 0)
			(layers "F.Cu" "F.Mask" "F.Paste")
			(net "Net_10830")
		)
		(pad "33" smd circle
			(at 4.400042 3.750056)
			(size 0 0)
			(layers "F.Cu" "F.Mask" "F.Paste")
			(net "USB_HUB2_TI_PWRCTL3_MRP_VDD33")
		)
		(pad "34" smd circle
			(at 4.400042 3.24993)
			(size 0 0)
			(layers "F.Cu" "F.Mask" "F.Paste")
			(net "USB_HUB2_TI_VDD33_MRP_PRT_CTL4_GANGPWR")
		)
		(pad "35" smd circle
			(at 4.400042 2.750058)
			(size 0 0)
			(layers "F.Cu" "F.Mask" "F.Paste")
			(net "USB_HUB2_TI_PWRCTL2_MRP_VDD12")
		)
		(pad "36" smd circle
			(at 4.400042 2.249932)
			(size 0 0)
			(layers "F.Cu" "F.Mask" "F.Paste")
			(net "Net_10831")
		)
		(pad "37" smd circle
			(at 4.400042 1.75006)
			(size 0 0)
			(layers "F.Cu" "F.Mask" "F.Paste")
			(net "SMB_USB_HUB2_TI_SDA_MRP_PRT_CTL2")
		)
		(pad "38" smd circle
			(at 4.400042 1.249934)
			(size 0 0)
			(layers "F.Cu" "F.Mask" "F.Paste")
			(net "SMB_USB_HUB2_TI_SCL_MRP_PRT_CTL1")
		)
		(pad "39" smd circle
			(at 4.400042 0.750062)
			(size 0 0)
			(layers "F.Cu" "F.Mask" "F.Paste")
			(net "USB_HUB2_TI_SMBUSZ_MRP_PROG_FUNC2")
		)
		(pad "40" smd circle
			(at 4.400042 0.249936)
			(size 0 0)
			(layers "F.Cu" "F.Mask" "F.Paste")
			(net "USB_HUB2_TI_FULLPWRMGMTZ_MRP_PROG_FUNC3")
		)
		(pad "41" smd circle
			(at 4.400042 -0.249936)
			(size 0 0)
			(layers "F.Cu" "F.Mask" "F.Paste")
			(net "USB_HUB2_TI_PWRCTL_POL_MRP_VBUS_DET")
		)
		(pad "42" smd circle
			(at 4.400042 -0.750062)
			(size 0 0)
			(layers "F.Cu" "F.Mask" "F.Paste")
			(net "USB_HUB2_TI_GANGED_MRP_I2C_SLV_CFG0")
		)
		(pad "43" smd circle
			(at 4.400042 -1.249934)
			(size 0 0)
			(layers "F.Cu" "F.Mask" "F.Paste")
			(net "USB_HUB2_TI_OVERCUR4_MRP_I2C_SLV_CFG1")
		)
		(pad "44" smd circle
			(at 4.400042 -1.75006)
			(size 0 0)
			(layers "F.Cu" "F.Mask" "F.Paste")
			(net "USB_HUB2_TI_OVERCUR3_MRP_CFG_BC_EN")
		)
	)
)
